# SCM (Grand Teton) — schematic netlist excerpt (pin names and nets, part order shuffled) for the footprints in the layout excerpt that follows; sources: Cadence DE-HDL packaged netlist, KiCad conversion of 12092022_DA0F0TMDCD0_F0T_Management_Board_D_brd_V3_OCP.brd

PC269  Q_CAP  22UF 4V 20% X6S  pkg 0805  page 56 : A = P1V0_AUX ; B = GND
C69  Q_CAP  0.1UF 25V 10% X7R  pkg 0402  page 16 : A = P1V8_STBY_PE_VCC18A ; B = GND

(kicad_pcb
	(version 20260206)
	(generator "pcbnew")
	(generator_version "10.0")
	(general
		(thickness 1.6)
		(legacy_teardrops no)
	)
	(paper "A4")
	(title_block
		(title "12092022_DA0F0TMDCD0_F0T_Management_Board_D_brd_V3_OCP.brd")
		(comment 1 "Grand Teton / footprints 1045-1046 of 1440")
	)
	(layers
		(0 "F.Cu" signal "TOP")
		(4 "In1.Cu" signal "GND")
		(6 "In2.Cu" signal "IN1")
		(8 "In3.Cu" signal "GND1")
		(10 "In4.Cu" signal "IN2")
		(12 "In5.Cu" signal "VCC")
		(14 "In6.Cu" signal "VCC1")
		(16 "In7.Cu" signal "IN3")
		(18 "In8.Cu" signal "GND2")
		(20 "In9.Cu" signal "IN4")
		(22 "In10.Cu" signal "GND3")
		(2 "B.Cu" signal "BOTTOM")
		(9 "F.Adhes" user "F.Adhesive")
		(11 "B.Adhes" user "B.Adhesive")
		(13 "F.Paste" user "Package Geometry/Pastemask Top")
		(15 "B.Paste" user "Package Geometry/Pastemask Bottom")
		(5 "F.SilkS" user "Ref Des/Silkscreen Top")
		(7 "B.SilkS" user "Ref Des/Silkscreen Bottom")
		(1 "F.Mask" user "Board Geometry/Soldermask Top")
		(3 "B.Mask" user "Board Geometry/Soldermask Bottom")
		(17 "Dwgs.User" user "User.Drawings")
		(19 "Cmts.User" user "User.Comments")
		(21 "Eco1.User" user "User.Eco1")
		(23 "Eco2.User" user "User.Eco2")
		(25 "Edge.Cuts" user "Board Geometry/Outline")
		(27 "Margin" user)
		(31 "F.CrtYd" user "Package Geometry/Place Bound Top")
		(29 "B.CrtYd" user "Package Geometry/Place Bound Bottom")
		(35 "F.Fab" user "Ref Des/Assembly Top")
		(33 "B.Fab" user "Ref Des/Assembly Bottom")
	)
	(footprint ""
		(layer "B.Cu")
		(at 58.679334 -54.416198 -90)
		(property "Reference" "C69"
			(at 0 0 90)
			(layer "B.SilkS")
			(hide yes)
			(effects
				(font
					(size 1.27 1.27)
				)
				(justify mirror)
			)
		)
		(property "Value" ""
			(at 0 0 90)
			(layer "B.Fab")
			(effects
				(font
					(size 1.27 1.27)
				)
				(justify mirror)
			)
		)
		(duplicate_pad_numbers_are_jumpers no)
		(fp_line
			(start -0.7874 0.4064)
			(end 0.7874 0.4064)
			(stroke
				(width 0.1524)
				(type default)
			)
			(layer "B.SilkS")
		)
		(fp_line
			(start 0.7874 0.4064)
			(end 0.7874 -0.4064)
			(stroke
				(width 0.1524)
				(type default)
			)
			(layer "B.SilkS")
		)
		(fp_line
			(start -0.7874 -0.4064)
			(end -0.7874 0.4064)
			(stroke
				(width 0.1524)
				(type default)
			)
			(layer "B.SilkS")
		)
		(fp_line
			(start 0.7874 -0.4064)
			(end -0.7874 -0.4064)
			(stroke
				(width 0.1524)
				(type default)
			)
			(layer "B.SilkS")
		)
		(fp_line
			(start -0.67945 0.3048)
			(end -0.120396 0.3048)
			(stroke
				(width 0.1)
				(type default)
			)
			(layer "B.Fab")
		)
		(fp_line
			(start -0.120396 0.3048)
			(end -0.120396 0.2794)
			(stroke
				(width 0.1)
				(type default)
			)
			(layer "B.Fab")
		)
		(fp_line
			(start 0.12065 0.3048)
			(end 0.67945 0.3048)
			(stroke
				(width 0.1)
				(type default)
			)
			(layer "B.Fab")
		)
		(fp_line
			(start 0.67945 0.3048)
			(end 0.67945 -0.305054)
			(stroke
				(width 0.1)
				(type default)
			)
			(layer "B.Fab")
		)
		(fp_line
			(start -0.120396 0.2794)
			(end 0.12065 0.2794)
			(stroke
				(width 0.1)
				(type default)
			)
			(layer "B.Fab")
		)
		(fp_line
			(start 0.12065 0.2794)
			(end 0.12065 0.3048)
			(stroke
				(width 0.1)
				(type default)
			)
			(layer "B.Fab")
		)
		(fp_line
			(start -0.12065 -0.2794)
			(end -0.12065 -0.3048)
			(stroke
				(width 0.1)
				(type default)
			)
			(layer "B.Fab")
		)
		(fp_line
			(start 0.12065 -0.2794)
			(end -0.12065 -0.2794)
			(stroke
				(width 0.1)
				(type default)
			)
			(layer "B.Fab")
		)
		(fp_line
			(start -0.67945 -0.3048)
			(end -0.67945 0.3048)
			(stroke
				(width 0.1)
				(type default)
			)
			(layer "B.Fab")
		)
		(fp_line
			(start -0.12065 -0.3048)
			(end -0.67945 -0.3048)
			(stroke
				(width 0.1)
				(type default)
			)
			(layer "B.Fab")
		)
		(fp_line
			(start 0.12065 -0.305054)
			(end 0.12065 -0.2794)
			(stroke
				(width 0.1)
				(type default)
			)
			(layer "B.Fab")
		)
		(fp_line
			(start 0.67945 -0.305054)
			(end 0.12065 -0.305054)
			(stroke
				(width 0.1)
				(type default)
			)
			(layer "B.Fab")
		)
		(pad "1" smd circle
			(at 0.40005 0 90)
			(size 0 0)
			(layers "B.Cu" "B.Mask" "B.Paste")
			(net "P1V8_STBY_PE_VCC18A")
		)
		(pad "2" smd circle
			(at -0.40005 0 90)
			(size 0 0)
			(layers "B.Cu" "B.Mask" "B.Paste")
			(net "GND")
		)
	)
	(footprint ""
		(layer "B.Cu")
		(at 20.066 -24.003 -90)
		(property "Reference" "PC269"
			(at 0 0 90)
			(layer "B.SilkS")
			(hide yes)
			(effects
				(font
					(size 1.27 1.27)
				)
				(justify mirror)
			)
		)
		(property "Value" ""
			(at 0 0 90)
			(layer "B.Fab")
			(effects
				(font
					(size 1.27 1.27)
				)
				(justify mirror)
			)
		)
		(duplicate_pad_numbers_are_jumpers no)
		(fp_line
			(start -1.651 0.8382)
			(end 1.651 0.8382)
			(stroke
				(width 0.1524)
				(type default)
			)
			(layer "B.SilkS")
		)
		(fp_line
			(start 0 0.8382)
			(end 0 -0.8382)
			(stroke
				(width 0.1524)
				(type default)
			)
			(layer "B.SilkS")
		)
		(fp_line
			(start 1.651 0.8382)
			(end 1.651 -0.8382)
			(stroke
				(width 0.1524)
				(type default)
			)
			(layer "B.SilkS")
		)
		(fp_line
			(start -1.651 -0.8382)
			(end -1.651 0.8382)
			(stroke
				(width 0.1524)
				(type default)
			)
			(layer "B.SilkS")
		)
		(fp_line
			(start 1.651 -0.8382)
			(end -1.651 -0.8382)
			(stroke
				(width 0.1524)
				(type default)
			)
			(layer "B.SilkS")
		)
		(fp_line
			(start -1.55956 0.7366)
			(end -1.55956 -0.7366)
			(stroke
				(width 0.1)
				(type default)
			)
			(layer "B.Fab")
		)
		(fp_line
			(start -1.524 0.7366)
			(end -1.55956 0.7366)
			(stroke
				(width 0.1)
				(type default)
			)
			(layer "B.Fab")
		)
		(fp_line
			(start 1.524 0.7366)
			(end -1.524 0.7366)
			(stroke
				(width 0.1)
				(type default)
			)
			(layer "B.Fab")
		)
		(fp_line
			(start 1.55956 0.7366)
			(end 1.524 0.7366)
			(stroke
				(width 0.1)
				(type default)
			)
			(layer "B.Fab")
		)
		(fp_line
			(start -1.55956 -0.7366)
			(end -1.524 -0.7366)
			(stroke
				(width 0.1)
				(type default)
			)
			(layer "B.Fab")
		)
		(fp_line
			(start -1.524 -0.7366)
			(end 1.524 -0.7366)
			(stroke
				(width 0.1)
				(type default)
			)
			(layer "B.Fab")
		)
		(fp_line
			(start 1.524 -0.7366)
			(end 1.55956 -0.7366)
			(stroke
				(width 0.1)
				(type default)
			)
			(layer "B.Fab")
		)
		(fp_line
			(start 1.55956 -0.7366)
			(end 1.55956 0.7366)
			(stroke
				(width 0.1)
				(type default)
			)
			(layer "B.Fab")
		)
		(pad "1" smd rect
			(at 0.94996 0 270)
			(size 1.1176 1.3716)
			(layers "B.Cu" "B.Mask" "B.Paste")
			(net "P1V0_AUX")
		)
		(pad "2" smd rect
			(at -0.94996 0 270)
			(size 1.1176 1.3716)
			(layers "B.Cu" "B.Mask" "B.Paste")
			(net "GND")
		)
	)
)
